# S9S_MB_2U (Grand Teton) — schematic netlist excerpt (pin names and nets, part order shuffled) for the footprints in the layout excerpt that follows; sources: Cadence DE-HDL packaged netlist, KiCad conversion of 03242023_DA0F0TMBIJ0_F0T_Motherboard_J_brd_V01_OCP.brd

R4636  Q_RES  200K 1% CHIP  pkg 0402LF  page 169 : A = USB3_PCH_RX_DP<4> ; B = GND
R1197  Q_RES  1K 1% EMPTY  pkg 0402LF  page 182 : A = GND ; B = PD_SUSCLK

(kicad_pcb
	(version 20260206)
	(generator "pcbnew")
	(generator_version "10.0")
	(general
		(thickness 1.6)
		(legacy_teardrops no)
	)
	(paper "A4")
	(title_block
		(title "03242023_DA0F0TMBIJ0_F0T_Motherboard_J_brd_V01_OCP.brd")
		(comment 1 "Grand Teton / footprints 5541-5542 of 6105")
	)
	(layers
		(0 "F.Cu" signal "TOP")
		(4 "In1.Cu" signal "GND")
		(6 "In2.Cu" signal "IN1")
		(8 "In3.Cu" signal "GND1")
		(10 "In4.Cu" signal "IN2")
		(12 "In5.Cu" signal "GND2")
		(14 "In6.Cu" signal "IN3")
		(16 "In7.Cu" signal "GND3")
		(18 "In8.Cu" signal "VCC")
		(20 "In9.Cu" signal "VCC1")
		(22 "In10.Cu" signal "GND4")
		(24 "In11.Cu" signal "IN4")
		(26 "In12.Cu" signal "GND5")
		(28 "In13.Cu" signal "IN5")
		(30 "In14.Cu" signal "GND6")
		(32 "In15.Cu" signal "IN6")
		(34 "In16.Cu" signal "GND7")
		(2 "B.Cu" signal "BOTTOM")
		(9 "F.Adhes" user "F.Adhesive")
		(11 "B.Adhes" user "B.Adhesive")
		(13 "F.Paste" user "Package Geometry/Pastemask Top")
		(15 "B.Paste" user "Package Geometry/Pastemask Bottom")
		(5 "F.SilkS" user "Ref Des/Silkscreen Top")
		(7 "B.SilkS" user "Ref Des/Silkscreen Bottom")
		(1 "F.Mask" user "Board Geometry/Soldermask Top")
		(3 "B.Mask" user "Board Geometry/Soldermask Bottom")
		(17 "Dwgs.User" user "User.Drawings")
		(19 "Cmts.User" user "User.Comments")
		(21 "Eco1.User" user "User.Eco1")
		(23 "Eco2.User" user "User.Eco2")
		(25 "Edge.Cuts" user "Board Geometry/Outline")
		(27 "Margin" user)
		(31 "F.CrtYd" user "Package Geometry/Place Bound Top")
		(29 "B.CrtYd" user "Package Geometry/Place Bound Bottom")
		(35 "F.Fab" user "Ref Des/Assembly Top")
		(33 "B.Fab" user "Ref Des/Assembly Bottom")
	)
	(footprint ""
		(layer "B.Cu")
		(at 133.5786 -28.6258 -90)
		(property "Reference" "R4636"
			(at 0 0 90)
			(layer "B.SilkS")
			(hide yes)
			(effects
				(font
					(size 1.27 1.27)
				)
				(justify mirror)
			)
		)
		(property "Value" ""
			(at 0 0 90)
			(layer "B.Fab")
			(effects
				(font
					(size 1.27 1.27)
				)
				(justify mirror)
			)
		)
		(duplicate_pad_numbers_are_jumpers no)
		(fp_line
			(start -0.7874 0.4064)
			(end 0.7874 0.4064)
			(stroke
				(width 0.1524)
				(type default)
			)
			(layer "B.SilkS")
		)
		(fp_line
			(start 0.7874 0.4064)
			(end 0.7874 -0.4064)
			(stroke
				(width 0.1524)
				(type default)
			)
			(layer "B.SilkS")
		)
		(fp_line
			(start -0.7874 -0.4064)
			(end -0.7874 0.4064)
			(stroke
				(width 0.1524)
				(type default)
			)
			(layer "B.SilkS")
		)
		(fp_line
			(start 0.7874 -0.4064)
			(end -0.7874 -0.4064)
			(stroke
				(width 0.1524)
				(type default)
			)
			(layer "B.SilkS")
		)
		(fp_line
			(start -0.67945 0.3048)
			(end -0.120396 0.3048)
			(stroke
				(width 0.1)
				(type default)
			)
			(layer "B.Fab")
		)
		(fp_line
			(start -0.120396 0.3048)
			(end -0.120396 0.2794)
			(stroke
				(width 0.1)
				(type default)
			)
			(layer "B.Fab")
		)
		(fp_line
			(start 0.12065 0.3048)
			(end 0.67945 0.3048)
			(stroke
				(width 0.1)
				(type default)
			)
			(layer "B.Fab")
		)
		(fp_line
			(start 0.67945 0.3048)
			(end 0.67945 -0.305054)
			(stroke
				(width 0.1)
				(type default)
			)
			(layer "B.Fab")
		)
		(fp_line
			(start -0.120396 0.2794)
			(end 0.12065 0.2794)
			(stroke
				(width 0.1)
				(type default)
			)
			(layer "B.Fab")
		)
		(fp_line
			(start 0.12065 0.2794)
			(end 0.12065 0.3048)
			(stroke
				(width 0.1)
				(type default)
			)
			(layer "B.Fab")
		)
		(fp_line
			(start -0.12065 -0.2794)
			(end -0.12065 -0.3048)
			(stroke
				(width 0.1)
				(type default)
			)
			(layer "B.Fab")
		)
		(fp_line
			(start 0.12065 -0.2794)
			(end -0.12065 -0.2794)
			(stroke
				(width 0.1)
				(type default)
			)
			(layer "B.Fab")
		)
		(fp_line
			(start -0.67945 -0.3048)
			(end -0.67945 0.3048)
			(stroke
				(width 0.1)
				(type default)
			)
			(layer "B.Fab")
		)
		(fp_line
			(start -0.12065 -0.3048)
			(end -0.67945 -0.3048)
			(stroke
				(width 0.1)
				(type default)
			)
			(layer "B.Fab")
		)
		(fp_line
			(start 0.12065 -0.305054)
			(end 0.12065 -0.2794)
			(stroke
				(width 0.1)
				(type default)
			)
			(layer "B.Fab")
		)
		(fp_line
			(start 0.67945 -0.305054)
			(end 0.12065 -0.305054)
			(stroke
				(width 0.1)
				(type default)
			)
			(layer "B.Fab")
		)
		(pad "1" smd circle
			(at 0.40005 0 90)
			(size 0 0)
			(layers "B.Cu" "B.Mask" "B.Paste")
			(net "USB3_PCH_RX_DP<4>")
		)
		(pad "2" smd circle
			(at -0.40005 0 90)
			(size 0 0)
			(layers "B.Cu" "B.Mask" "B.Paste")
			(net "GND")
		)
	)
	(footprint ""
		(layer "B.Cu")
		(at 317.902844 -31.523178 180)
		(property "Reference" "R1197"
			(at 0 0 0)
			(layer "B.SilkS")
			(hide yes)
			(effects
				(font
					(size 1.27 1.27)
				)
				(justify mirror)
			)
		)
		(property "Value" ""
			(at 0 0 0)
			(layer "B.Fab")
			(effects
				(font
					(size 1.27 1.27)
				)
				(justify mirror)
			)
		)
		(duplicate_pad_numbers_are_jumpers no)
		(fp_line
			(start 0.7874 0.4064)
			(end 0.7874 -0.4064)
			(stroke
				(width 0.1524)
				(type default)
			)
			(layer "B.SilkS")
		)
		(fp_line
			(start 0.7874 -0.4064)
			(end -0.7874 -0.4064)
			(stroke
				(width 0.1524)
				(type default)
			)
			(layer "B.SilkS")
		)
		(fp_line
			(start -0.7874 0.4064)
			(end 0.7874 0.4064)
			(stroke
				(width 0.1524)
				(type default)
			)
			(layer "B.SilkS")
		)
		(fp_line
			(start -0.7874 -0.4064)
			(end -0.7874 0.4064)
			(stroke
				(width 0.1524)
				(type default)
			)
			(layer "B.SilkS")
		)
		(fp_line
			(start 0.67945 0.3048)
			(end 0.67945 -0.305054)
			(stroke
				(width 0.1)
				(type default)
			)
			(layer "B.Fab")
		)
		(fp_line
			(start 0.67945 -0.305054)
			(end 0.12065 -0.305054)
			(stroke
				(width 0.1)
				(type default)
			)
			(layer "B.Fab")
		)
		(fp_line
			(start 0.12065 0.3048)
			(end 0.67945 0.3048)
			(stroke
				(width 0.1)
				(type default)
			)
			(layer "B.Fab")
		)
		(fp_line
			(start 0.12065 0.2794)
			(end 0.12065 0.3048)
			(stroke
				(width 0.1)
				(type default)
			)
			(layer "B.Fab")
		)
		(fp_line
			(start 0.12065 -0.2794)
			(end -0.12065 -0.2794)
			(stroke
				(width 0.1)
				(type default)
			)
			(layer "B.Fab")
		)
		(fp_line
			(start 0.12065 -0.305054)
			(end 0.12065 -0.2794)
			(stroke
				(width 0.1)
				(type default)
			)
			(layer "B.Fab")
		)
		(fp_line
			(start -0.120396 0.3048)
			(end -0.120396 0.2794)
			(stroke
				(width 0.1)
				(type default)
			)
			(layer "B.Fab")
		)
		(fp_line
			(start -0.120396 0.2794)
			(end 0.12065 0.2794)
			(stroke
				(width 0.1)
				(type default)
			)
			(layer "B.Fab")
		)
		(fp_line
			(start -0.12065 -0.2794)
			(end -0.12065 -0.3048)
			(stroke
				(width 0.1)
				(type default)
			)
			(layer "B.Fab")
		)
		(fp_line
			(start -0.12065 -0.3048)
			(end -0.67945 -0.3048)
			(stroke
				(width 0.1)
				(type default)
			)
			(layer "B.Fab")
		)
		(fp_line
			(start -0.67945 0.3048)
			(end -0.120396 0.3048)
			(stroke
				(width 0.1)
				(type default)
			)
			(layer "B.Fab")
		)
		(fp_line
			(start -0.67945 -0.3048)
			(end -0.67945 0.3048)
			(stroke
				(width 0.1)
				(type default)
			)
			(layer "B.Fab")
		)
		(pad "1" smd circle
			(at 0.40005 0)
			(size 0 0)
			(layers "B.Cu" "B.Mask" "B.Paste")
			(net "GND")
		)
		(pad "2" smd circle
			(at -0.40005 0)
			(size 0 0)
			(layers "B.Cu" "B.Mask" "B.Paste")
			(net "PD_SUSCLK")
		)
	)
)
